(kicad_pcb
	(version 20260206)
	(generator "pcbnew")
	(generator_version "10.0")
	(general
		(thickness 1.6)
		(legacy_teardrops no)
	)
	(paper "A4")
	(title_block
		(title "01162023_DA0F0TEBIF0_F0T_Expander_BD_F_brd_V02_OCP.brd")
		(comment 1 "Grand Teton / footprints 3210-3216 of 9728")
	)
	(layers
		(0 "F.Cu" signal "TOP")
		(4 "In1.Cu" signal "GND")
		(6 "In2.Cu" signal "VCC")
		(8 "In3.Cu" signal "VCC1")
		(10 "In4.Cu" signal "GND1")
		(12 "In5.Cu" signal "IN1")
		(14 "In6.Cu" signal "GND2")
		(16 "In7.Cu" signal "IN2")
		(18 "In8.Cu" signal "GND3")
		(20 "In9.Cu" signal "IN3")
		(22 "In10.Cu" signal "GND4")
		(24 "In11.Cu" signal "IN4")
		(26 "In12.Cu" signal "GND5")
		(28 "In13.Cu" signal "IN5")
		(30 "In14.Cu" signal "GND6")
		(32 "In15.Cu" signal "IN6")
		(34 "In16.Cu" signal "GND7")
		(2 "B.Cu" signal "BOTTOM")
		(9 "F.Adhes" user "F.Adhesive")
		(11 "B.Adhes" user "B.Adhesive")
		(13 "F.Paste" user "Package Geometry/Pastemask Top")
		(15 "B.Paste" user "Package Geometry/Pastemask Bottom")
		(5 "F.SilkS" user "Ref Des/Silkscreen Top")
		(7 "B.SilkS" user "Ref Des/Silkscreen Bottom")
		(1 "F.Mask" user "Board Geometry/Soldermask Top")
		(3 "B.Mask" user "Board Geometry/Soldermask Bottom")
		(17 "Dwgs.User" user "User.Drawings")
		(19 "Cmts.User" user "User.Comments")
		(21 "Eco1.User" user "User.Eco1")
		(23 "Eco2.User" user "User.Eco2")
		(25 "Edge.Cuts" user "Board Geometry/Outline")
		(27 "Margin" user)
		(31 "F.CrtYd" user "Package Geometry/Place Bound Top")
		(29 "B.CrtYd" user "Package Geometry/Place Bound Bottom")
		(35 "F.Fab" user "Ref Des/Assembly Top")
		(33 "B.Fab" user "Ref Des/Assembly Bottom")
	)
	(footprint ""
		(layer "F.Cu")
		(at 5.04317 -34.896298 90)
		(property "Reference" "R1631"
			(at 0 0 90)
			(layer "F.SilkS")
			(hide yes)
			(effects
				(font
					(size 1.27 1.27)
				)
			)
		)
		(property "Value" ""
			(at 0 0 90)
			(layer "F.Fab")
			(effects
				(font
					(size 1.27 1.27)
				)
			)
		)
		(duplicate_pad_numbers_are_jumpers no)
		(fp_line
			(start 0.7874 -0.4064)
			(end 0.7874 0.4064)
			(stroke
				(width 0.1524)
				(type default)
			)
			(layer "F.SilkS")
		)
		(fp_line
			(start -0.7874 -0.4064)
			(end 0.7874 -0.4064)
			(stroke
				(width 0.1524)
				(type default)
			)
			(layer "F.SilkS")
		)
		(fp_line
			(start 0.7874 0.4064)
			(end -0.7874 0.4064)
			(stroke
				(width 0.1524)
				(type default)
			)
			(layer "F.SilkS")
		)
		(fp_line
			(start -0.7874 0.4064)
			(end -0.7874 -0.4064)
			(stroke
				(width 0.1524)
				(type default)
			)
			(layer "F.SilkS")
		)
		(fp_line
			(start -0.12065 -0.305054)
			(end -0.12065 -0.2794)
			(stroke
				(width 0.1)
				(type default)
			)
			(layer "F.Fab")
		)
		(fp_line
			(start -0.67945 -0.305054)
			(end -0.12065 -0.305054)
			(stroke
				(width 0.1)
				(type default)
			)
			(layer "F.Fab")
		)
		(fp_line
			(start 0.67945 -0.3048)
			(end 0.67945 0.3048)
			(stroke
				(width 0.1)
				(type default)
			)
			(layer "F.Fab")
		)
		(fp_line
			(start 0.12065 -0.3048)
			(end 0.67945 -0.3048)
			(stroke
				(width 0.1)
				(type default)
			)
			(layer "F.Fab")
		)
		(fp_line
			(start 0.12065 -0.2794)
			(end 0.12065 -0.3048)
			(stroke
				(width 0.1)
				(type default)
			)
			(layer "F.Fab")
		)
		(fp_line
			(start -0.12065 -0.2794)
			(end 0.12065 -0.2794)
			(stroke
				(width 0.1)
				(type default)
			)
			(layer "F.Fab")
		)
		(fp_line
			(start 0.120396 0.2794)
			(end -0.12065 0.2794)
			(stroke
				(width 0.1)
				(type default)
			)
			(layer "F.Fab")
		)
		(fp_line
			(start -0.12065 0.2794)
			(end -0.12065 0.3048)
			(stroke
				(width 0.1)
				(type default)
			)
			(layer "F.Fab")
		)
		(fp_line
			(start 0.67945 0.3048)
			(end 0.120396 0.3048)
			(stroke
				(width 0.1)
				(type default)
			)
			(layer "F.Fab")
		)
		(fp_line
			(start 0.120396 0.3048)
			(end 0.120396 0.2794)
			(stroke
				(width 0.1)
				(type default)
			)
			(layer "F.Fab")
		)
		(fp_line
			(start -0.12065 0.3048)
			(end -0.67945 0.3048)
			(stroke
				(width 0.1)
				(type default)
			)
			(layer "F.Fab")
		)
		(fp_line
			(start -0.67945 0.3048)
			(end -0.67945 -0.305054)
			(stroke
				(width 0.1)
				(type default)
			)
			(layer "F.Fab")
		)
		(pad "1" smd circle
			(at -0.40005 0 90)
			(size 0 0)
			(layers "F.Cu" "F.Mask" "F.Paste")
			(net "SMB_SSD0_ISO_EN")
		)
		(pad "2" smd circle
			(at 0.40005 0 90)
			(size 0 0)
			(layers "F.Cu" "F.Mask" "F.Paste")
			(net "P3V3_AUX")
		)
	)
	(footprint ""
		(layer "F.Cu")
		(at 29.872178 -32.848042 90)
		(property "Reference" "PC672"
			(at 0 0 90)
			(layer "F.SilkS")
			(hide yes)
			(effects
				(font
					(size 1.27 1.27)
				)
			)
		)
		(property "Value" ""
			(at 0 0 90)
			(layer "F.Fab")
			(effects
				(font
					(size 1.27 1.27)
				)
			)
		)
		(duplicate_pad_numbers_are_jumpers no)
		(fp_line
			(start 0.7874 -0.4064)
			(end 0.7874 0.4064)
			(stroke
				(width 0.1524)
				(type default)
			)
			(layer "F.SilkS")
		)
		(fp_line
			(start -0.7874 -0.4064)
			(end 0.7874 -0.4064)
			(stroke
				(width 0.1524)
				(type default)
			)
			(layer "F.SilkS")
		)
		(fp_line
			(start 0.7874 0.4064)
			(end -0.7874 0.4064)
			(stroke
				(width 0.1524)
				(type default)
			)
			(layer "F.SilkS")
		)
		(fp_line
			(start -0.7874 0.4064)
			(end -0.7874 -0.4064)
			(stroke
				(width 0.1524)
				(type default)
			)
			(layer "F.SilkS")
		)
		(fp_line
			(start -0.12065 -0.305054)
			(end -0.12065 -0.2794)
			(stroke
				(width 0.1)
				(type default)
			)
			(layer "F.Fab")
		)
		(fp_line
			(start -0.67945 -0.305054)
			(end -0.12065 -0.305054)
			(stroke
				(width 0.1)
				(type default)
			)
			(layer "F.Fab")
		)
		(fp_line
			(start 0.67945 -0.3048)
			(end 0.67945 0.3048)
			(stroke
				(width 0.1)
				(type default)
			)
			(layer "F.Fab")
		)
		(fp_line
			(start 0.12065 -0.3048)
			(end 0.67945 -0.3048)
			(stroke
				(width 0.1)
				(type default)
			)
			(layer "F.Fab")
		)
		(fp_line
			(start 0.12065 -0.2794)
			(end 0.12065 -0.3048)
			(stroke
				(width 0.1)
				(type default)
			)
			(layer "F.Fab")
		)
		(fp_line
			(start -0.12065 -0.2794)
			(end 0.12065 -0.2794)
			(stroke
				(width 0.1)
				(type default)
			)
			(layer "F.Fab")
		)
		(fp_line
			(start 0.120396 0.2794)
			(end -0.12065 0.2794)
			(stroke
				(width 0.1)
				(type default)
			)
			(layer "F.Fab")
		)
		(fp_line
			(start -0.12065 0.2794)
			(end -0.12065 0.3048)
			(stroke
				(width 0.1)
				(type default)
			)
			(layer "F.Fab")
		)
		(fp_line
			(start 0.67945 0.3048)
			(end 0.120396 0.3048)
			(stroke
				(width 0.1)
				(type default)
			)
			(layer "F.Fab")
		)
		(fp_line
			(start 0.120396 0.3048)
			(end 0.120396 0.2794)
			(stroke
				(width 0.1)
				(type default)
			)
			(layer "F.Fab")
		)
		(fp_line
			(start -0.12065 0.3048)
			(end -0.67945 0.3048)
			(stroke
				(width 0.1)
				(type default)
			)
			(layer "F.Fab")
		)
		(fp_line
			(start -0.67945 0.3048)
			(end -0.67945 -0.305054)
			(stroke
				(width 0.1)
				(type default)
			)
			(layer "F.Fab")
		)
		(pad "1" smd circle
			(at -0.40005 0 90)
			(size 0 0)
			(layers "F.Cu" "F.Mask" "F.Paste")
			(net "P3V3_SSD1_CO_GATE")
		)
		(pad "2" smd circle
			(at 0.40005 0 90)
			(size 0 0)
			(layers "F.Cu" "F.Mask" "F.Paste")
			(net "GND")
		)
	)
	(footprint ""
		(layer "F.Cu")
		(at 136.708388 -350.098614 90)
		(property "Reference" "C2265"
			(at 0 0 90)
			(layer "F.SilkS")
			(hide yes)
			(effects
				(font
					(size 1.27 1.27)
				)
			)
		)
		(property "Value" ""
			(at 0 0 90)
			(layer "F.Fab")
			(effects
				(font
					(size 1.27 1.27)
				)
			)
		)
		(duplicate_pad_numbers_are_jumpers no)
		(fp_line
			(start 0.299974 -0.150114)
			(end 0.299974 0.150114)
			(stroke
				(width 0.1)
				(type default)
			)
			(layer "F.Fab")
		)
		(fp_line
			(start -0.299974 -0.150114)
			(end 0.299974 -0.150114)
			(stroke
				(width 0.1)
				(type default)
			)
			(layer "F.Fab")
		)
		(fp_line
			(start 0.299974 0.150114)
			(end -0.299974 0.150114)
			(stroke
				(width 0.1)
				(type default)
			)
			(layer "F.Fab")
		)
		(fp_line
			(start -0.299974 0.150114)
			(end -0.299974 -0.150114)
			(stroke
				(width 0.1)
				(type default)
			)
			(layer "F.Fab")
		)
		(pad "1" smd rect
			(at -0.2667 0 90)
			(size 0.3048 0.381)
			(layers "F.Cu" "F.Mask" "F.Paste")
			(net "P5E_PEX1_STN5_TX_DP<84>")
		)
		(pad "2" smd rect
			(at 0.2667 0 90)
			(size 0.3048 0.381)
			(layers "F.Cu" "F.Mask" "F.Paste")
			(net "P5E_PEX1_STN5_TX_C_DP<84>")
		)
	)
	(footprint ""
		(layer "F.Cu")
		(at 323.917818 -220.849698 180)
		(property "Reference" "R2982"
			(at 0 0 180)
			(layer "F.SilkS")
			(hide yes)
			(effects
				(font
					(size 1.27 1.27)
				)
			)
		)
		(property "Value" ""
			(at 0 0 180)
			(layer "F.Fab")
			(effects
				(font
					(size 1.27 1.27)
				)
			)
		)
		(duplicate_pad_numbers_are_jumpers no)
		(fp_line
			(start 0.7874 0.4064)
			(end -0.7874 0.4064)
			(stroke
				(width 0.1524)
				(type default)
			)
			(layer "F.SilkS")
		)
		(fp_line
			(start 0.7874 -0.4064)
			(end 0.7874 0.4064)
			(stroke
				(width 0.1524)
				(type default)
			)
			(layer "F.SilkS")
		)
		(fp_line
			(start -0.7874 0.4064)
			(end -0.7874 -0.4064)
			(stroke
				(width 0.1524)
				(type default)
			)
			(layer "F.SilkS")
		)
		(fp_line
			(start -0.7874 -0.4064)
			(end 0.7874 -0.4064)
			(stroke
				(width 0.1524)
				(type default)
			)
			(layer "F.SilkS")
		)
		(fp_line
			(start 0.67945 0.3048)
			(end 0.120396 0.3048)
			(stroke
				(width 0.1)
				(type default)
			)
			(layer "F.Fab")
		)
		(fp_line
			(start 0.67945 -0.3048)
			(end 0.67945 0.3048)
			(stroke
				(width 0.1)
				(type default)
			)
			(layer "F.Fab")
		)
		(fp_line
			(start 0.12065 -0.2794)
			(end 0.12065 -0.3048)
			(stroke
				(width 0.1)
				(type default)
			)
			(layer "F.Fab")
		)
		(fp_line
			(start 0.12065 -0.3048)
			(end 0.67945 -0.3048)
			(stroke
				(width 0.1)
				(type default)
			)
			(layer "F.Fab")
		)
		(fp_line
			(start 0.120396 0.3048)
			(end 0.120396 0.2794)
			(stroke
				(width 0.1)
				(type default)
			)
			(layer "F.Fab")
		)
		(fp_line
			(start 0.120396 0.2794)
			(end -0.12065 0.2794)
			(stroke
				(width 0.1)
				(type default)
			)
			(layer "F.Fab")
		)
		(fp_line
			(start -0.12065 0.3048)
			(end -0.67945 0.3048)
			(stroke
				(width 0.1)
				(type default)
			)
			(layer "F.Fab")
		)
		(fp_line
			(start -0.12065 0.2794)
			(end -0.12065 0.3048)
			(stroke
				(width 0.1)
				(type default)
			)
			(layer "F.Fab")
		)
		(fp_line
			(start -0.12065 -0.2794)
			(end 0.12065 -0.2794)
			(stroke
				(width 0.1)
				(type default)
			)
			(layer "F.Fab")
		)
		(fp_line
			(start -0.12065 -0.305054)
			(end -0.12065 -0.2794)
			(stroke
				(width 0.1)
				(type default)
			)
			(layer "F.Fab")
		)
		(fp_line
			(start -0.67945 0.3048)
			(end -0.67945 -0.305054)
			(stroke
				(width 0.1)
				(type default)
			)
			(layer "F.Fab")
		)
		(fp_line
			(start -0.67945 -0.305054)
			(end -0.12065 -0.305054)
			(stroke
				(width 0.1)
				(type default)
			)
			(layer "F.Fab")
		)
		(pad "1" smd circle
			(at -0.40005 0 180)
			(size 0 0)
			(layers "F.Cu" "F.Mask" "F.Paste")
			(net "LED_POSTCODE_4")
		)
		(pad "2" smd circle
			(at 0.40005 0 180)
			(size 0 0)
			(layers "F.Cu" "F.Mask" "F.Paste")
			(net "LED_POSTCODE_R_4")
		)
	)
	(footprint ""
		(layer "F.Cu")
		(at 319.696084 -387.942836 180)
		(property "Reference" "R1852"
			(at 0 0 180)
			(layer "F.SilkS")
			(hide yes)
			(effects
				(font
					(size 1.27 1.27)
				)
			)
		)
		(property "Value" ""
			(at 0 0 180)
			(layer "F.Fab")
			(effects
				(font
					(size 1.27 1.27)
				)
			)
		)
		(duplicate_pad_numbers_are_jumpers no)
		(fp_line
			(start 0.7874 0.4064)
			(end -0.7874 0.4064)
			(stroke
				(width 0.1524)
				(type default)
			)
			(layer "F.SilkS")
		)
		(fp_line
			(start 0.7874 -0.4064)
			(end 0.7874 0.4064)
			(stroke
				(width 0.1524)
				(type default)
			)
			(layer "F.SilkS")
		)
		(fp_line
			(start -0.7874 0.4064)
			(end -0.7874 -0.4064)
			(stroke
				(width 0.1524)
				(type default)
			)
			(layer "F.SilkS")
		)
		(fp_line
			(start -0.7874 -0.4064)
			(end 0.7874 -0.4064)
			(stroke
				(width 0.1524)
				(type default)
			)
			(layer "F.SilkS")
		)
		(fp_line
			(start 0.67945 0.3048)
			(end 0.120396 0.3048)
			(stroke
				(width 0.1)
				(type default)
			)
			(layer "F.Fab")
		)
		(fp_line
			(start 0.67945 -0.3048)
			(end 0.67945 0.3048)
			(stroke
				(width 0.1)
				(type default)
			)
			(layer "F.Fab")
		)
		(fp_line
			(start 0.12065 -0.2794)
			(end 0.12065 -0.3048)
			(stroke
				(width 0.1)
				(type default)
			)
			(layer "F.Fab")
		)
		(fp_line
			(start 0.12065 -0.3048)
			(end 0.67945 -0.3048)
			(stroke
				(width 0.1)
				(type default)
			)
			(layer "F.Fab")
		)
		(fp_line
			(start 0.120396 0.3048)
			(end 0.120396 0.2794)
			(stroke
				(width 0.1)
				(type default)
			)
			(layer "F.Fab")
		)
		(fp_line
			(start 0.120396 0.2794)
			(end -0.12065 0.2794)
			(stroke
				(width 0.1)
				(type default)
			)
			(layer "F.Fab")
		)
		(fp_line
			(start -0.12065 0.3048)
			(end -0.67945 0.3048)
			(stroke
				(width 0.1)
				(type default)
			)
			(layer "F.Fab")
		)
		(fp_line
			(start -0.12065 0.2794)
			(end -0.12065 0.3048)
			(stroke
				(width 0.1)
				(type default)
			)
			(layer "F.Fab")
		)
		(fp_line
			(start -0.12065 -0.2794)
			(end 0.12065 -0.2794)
			(stroke
				(width 0.1)
				(type default)
			)
			(layer "F.Fab")
		)
		(fp_line
			(start -0.12065 -0.305054)
			(end -0.12065 -0.2794)
			(stroke
				(width 0.1)
				(type default)
			)
			(layer "F.Fab")
		)
		(fp_line
			(start -0.67945 0.3048)
			(end -0.67945 -0.305054)
			(stroke
				(width 0.1)
				(type default)
			)
			(layer "F.Fab")
		)
		(fp_line
			(start -0.67945 -0.305054)
			(end -0.12065 -0.305054)
			(stroke
				(width 0.1)
				(type default)
			)
			(layer "F.Fab")
		)
		(pad "1" smd circle
			(at -0.40005 0 180)
			(size 0 0)
			(layers "F.Cu" "F.Mask" "F.Paste")
			(net "GPU_FPGA_OVERT_R_N")
		)
		(pad "2" smd circle
			(at 0.40005 0 180)
			(size 0 0)
			(layers "F.Cu" "F.Mask" "F.Paste")
			(net "GPU_FPGA_OVERT_N")
		)
	)
	(footprint ""
		(layer "F.Cu")
		(at 403.156166 -32.848042 -90)
		(property "Reference" "R6114"
			(at 0 0 270)
			(layer "F.SilkS")
			(hide yes)
			(effects
				(font
					(size 1.27 1.27)
				)
			)
		)
		(property "Value" ""
			(at 0 0 270)
			(layer "F.Fab")
			(effects
				(font
					(size 1.27 1.27)
				)
			)
		)
		(duplicate_pad_numbers_are_jumpers no)
		(fp_line
			(start -0.7874 0.4064)
			(end -0.7874 -0.4064)
			(stroke
				(width 0.1524)
				(type default)
			)
			(layer "F.SilkS")
		)
		(fp_line
			(start 0.7874 0.4064)
			(end -0.7874 0.4064)
			(stroke
				(width 0.1524)
				(type default)
			)
			(layer "F.SilkS")
		)
		(fp_line
			(start -0.7874 -0.4064)
			(end 0.7874 -0.4064)
			(stroke
				(width 0.1524)
				(type default)
			)
			(layer "F.SilkS")
		)
		(fp_line
			(start 0.7874 -0.4064)
			(end 0.7874 0.4064)
			(stroke
				(width 0.1524)
				(type default)
			)
			(layer "F.SilkS")
		)
		(fp_line
			(start -0.67945 0.3048)
			(end -0.67945 -0.305054)
			(stroke
				(width 0.1)
				(type default)
			)
			(layer "F.Fab")
		)
		(fp_line
			(start -0.12065 0.3048)
			(end -0.67945 0.3048)
			(stroke
				(width 0.1)
				(type default)
			)
			(layer "F.Fab")
		)
		(fp_line
			(start 0.120396 0.3048)
			(end 0.120396 0.2794)
			(stroke
				(width 0.1)
				(type default)
			)
			(layer "F.Fab")
		)
		(fp_line
			(start 0.67945 0.3048)
			(end 0.120396 0.3048)
			(stroke
				(width 0.1)
				(type default)
			)
			(layer "F.Fab")
		)
		(fp_line
			(start -0.12065 0.2794)
			(end -0.12065 0.3048)
			(stroke
				(width 0.1)
				(type default)
			)
			(layer "F.Fab")
		)
		(fp_line
			(start 0.120396 0.2794)
			(end -0.12065 0.2794)
			(stroke
				(width 0.1)
				(type default)
			)
			(layer "F.Fab")
		)
		(fp_line
			(start -0.12065 -0.2794)
			(end 0.12065 -0.2794)
			(stroke
				(width 0.1)
				(type default)
			)
			(layer "F.Fab")
		)
		(fp_line
			(start 0.12065 -0.2794)
			(end 0.12065 -0.3048)
			(stroke
				(width 0.1)
				(type default)
			)
			(layer "F.Fab")
		)
		(fp_line
			(start 0.12065 -0.3048)
			(end 0.67945 -0.3048)
			(stroke
				(width 0.1)
				(type default)
			)
			(layer "F.Fab")
		)
		(fp_line
			(start 0.67945 -0.3048)
			(end 0.67945 0.3048)
			(stroke
				(width 0.1)
				(type default)
			)
			(layer "F.Fab")
		)
		(fp_line
			(start -0.67945 -0.305054)
			(end -0.12065 -0.305054)
			(stroke
				(width 0.1)
				(type default)
			)
			(layer "F.Fab")
		)
		(fp_line
			(start -0.12065 -0.305054)
			(end -0.12065 -0.2794)
			(stroke
				(width 0.1)
				(type default)
			)
			(layer "F.Fab")
		)
		(pad "1" smd circle
			(at -0.40005 0 270)
			(size 0 0)
			(layers "F.Cu" "F.Mask" "F.Paste")
			(net "SSD14_AUX_P3V3_EN_R")
		)
		(pad "2" smd circle
			(at 0.40005 0 270)
			(size 0 0)
			(layers "F.Cu" "F.Mask" "F.Paste")
			(net "P3V3_SSD14_CO_EN")
		)
	)
	(footprint ""
		(layer "F.Cu")
		(at 363.474 -198.755)
		(property "Reference" "R4667"
			(at 0 0 0)
			(layer "F.SilkS")
			(hide yes)
			(effects
				(font
					(size 1.27 1.27)
				)
			)
		)
		(property "Value" ""
			(at 0 0 0)
			(layer "F.Fab")
			(effects
				(font
					(size 1.27 1.27)
				)
			)
		)
		(duplicate_pad_numbers_are_jumpers no)
		(fp_line
			(start -0.7874 -0.4064)
			(end 0.7874 -0.4064)
			(stroke
				(width 0.1524)
				(type default)
			)
			(layer "F.SilkS")
		)
		(fp_line
			(start -0.7874 0.4064)
			(end -0.7874 -0.4064)
			(stroke
				(width 0.1524)
				(type default)
			)
			(layer "F.SilkS")
		)
		(fp_line
			(start 0.7874 -0.4064)
			(end 0.7874 0.4064)
			(stroke
				(width 0.1524)
				(type default)
			)
			(layer "F.SilkS")
		)
		(fp_line
			(start 0.7874 0.4064)
			(end -0.7874 0.4064)
			(stroke
				(width 0.1524)
				(type default)
			)
			(layer "F.SilkS")
		)
		(fp_line
			(start -0.67945 -0.305054)
			(end -0.12065 -0.305054)
			(stroke
				(width 0.1)
				(type default)
			)
			(layer "F.Fab")
		)
		(fp_line
			(start -0.67945 0.3048)
			(end -0.67945 -0.305054)
			(stroke
				(width 0.1)
				(type default)
			)
			(layer "F.Fab")
		)
		(fp_line
			(start -0.12065 -0.305054)
			(end -0.12065 -0.2794)
			(stroke
				(width 0.1)
				(type default)
			)
			(layer "F.Fab")
		)
		(fp_line
			(start -0.12065 -0.2794)
			(end 0.12065 -0.2794)
			(stroke
				(width 0.1)
				(type default)
			)
			(layer "F.Fab")
		)
		(fp_line
			(start -0.12065 0.2794)
			(end -0.12065 0.3048)
			(stroke
				(width 0.1)
				(type default)
			)
			(layer "F.Fab")
		)
		(fp_line
			(start -0.12065 0.3048)
			(end -0.67945 0.3048)
			(stroke
				(width 0.1)
				(type default)
			)
			(layer "F.Fab")
		)
		(fp_line
			(start 0.120396 0.2794)
			(end -0.12065 0.2794)
			(stroke
				(width 0.1)
				(type default)
			)
			(layer "F.Fab")
		)
		(fp_line
			(start 0.120396 0.3048)
			(end 0.120396 0.2794)
			(stroke
				(width 0.1)
				(type default)
			)
			(layer "F.Fab")
		)
		(fp_line
			(start 0.12065 -0.3048)
			(end 0.67945 -0.3048)
			(stroke
				(width 0.1)
				(type default)
			)
			(layer "F.Fab")
		)
		(fp_line
			(start 0.12065 -0.2794)
			(end 0.12065 -0.3048)
			(stroke
				(width 0.1)
				(type default)
			)
			(layer "F.Fab")
		)
		(fp_line
			(start 0.67945 -0.3048)
			(end 0.67945 0.3048)
			(stroke
				(width 0.1)
				(type default)
			)
			(layer "F.Fab")
		)
		(fp_line
			(start 0.67945 0.3048)
			(end 0.120396 0.3048)
			(stroke
				(width 0.1)
				(type default)
			)
			(layer "F.Fab")
		)
		(pad "1" smd circle
			(at -0.40005 0)
			(size 0 0)
			(layers "F.Cu" "F.Mask" "F.Paste")
			(net "P3V3_AUX")
		)
		(pad "2" smd circle
			(at 0.40005 0)
			(size 0 0)
			(layers "F.Cu" "F.Mask" "F.Paste")
			(net "RST_PEX_SSD4_PERST_R_N")
		)
	)
)
